(kicad_pcb
	(version 20260206)
	(generator "pcbnew")
	(generator_version "10.0")
	(general
		(thickness 1.6)
		(legacy_teardrops no)
	)
	(paper "A4")
	(title_block
		(title "04192023_DAF0TMB3IC0_F0TG_MB_C_brd_V02_OCP.brd")
		(comment 1 "Grand Teton / footprint 3955 of 8354 (U25), pads 3444-3554 of 6102")
	)
	(layers
		(0 "F.Cu" signal "TOP")
		(4 "In1.Cu" signal "GND")
		(6 "In2.Cu" signal "IN1")
		(8 "In3.Cu" signal "GND1")
		(10 "In4.Cu" signal "IN2")
		(12 "In5.Cu" signal "GND2")
		(14 "In6.Cu" signal "IN3")
		(16 "In7.Cu" signal "GND3")
		(18 "In8.Cu" signal "VCC")
		(20 "In9.Cu" signal "VCC1")
		(22 "In10.Cu" signal "GND4")
		(24 "In11.Cu" signal "IN4")
		(26 "In12.Cu" signal "GND5")
		(28 "In13.Cu" signal "IN5")
		(30 "In14.Cu" signal "GND6")
		(32 "In15.Cu" signal "IN6")
		(34 "In16.Cu" signal "GND7")
		(2 "B.Cu" signal "BOTTOM")
		(9 "F.Adhes" user "F.Adhesive")
		(11 "B.Adhes" user "B.Adhesive")
		(13 "F.Paste" user "Package Geometry/Pastemask Top")
		(15 "B.Paste" user "Package Geometry/Pastemask Bottom")
		(5 "F.SilkS" user "Ref Des/Silkscreen Top")
		(7 "B.SilkS" user "Ref Des/Silkscreen Bottom")
		(1 "F.Mask" user "Board Geometry/Soldermask Top")
		(3 "B.Mask" user "Board Geometry/Soldermask Bottom")
		(17 "Dwgs.User" user "User.Drawings")
		(19 "Cmts.User" user "User.Comments")
		(21 "Eco1.User" user "User.Eco1")
		(23 "Eco2.User" user "User.Eco2")
		(25 "Edge.Cuts" user "Board Geometry/Outline")
		(27 "Margin" user)
		(31 "F.CrtYd" user "Package Geometry/Place Bound Top")
		(29 "B.CrtYd" user "Package Geometry/Place Bound Bottom")
		(35 "F.Fab" user "Ref Des/Assembly Top")
		(33 "B.Fab" user "Ref Des/Assembly Bottom")
	)
	(footprint ""
		(layer "F.Cu")
		(at 359.867962 -258.880102 180)
		(property "Reference" "U25"
			(at -45.78477 -62.086744 0)
			(unlocked yes)
			(layer "F.SilkS")
			(effects
				(font
					(size 0.7874 0.5842)
					(thickness 0.1524)
				)
			)
		)
		(property "Value" ""
			(at 0 0 180)
			(layer "F.Fab")
			(effects
				(font
					(size 1.27 1.27)
				)
			)
		)
		(duplicate_pad_numbers_are_jumpers no)
		(pad "CJ63" smd circle
			(at 22.880066 20.610068 180)
			(size 0.450088 0.450088)
			(layers "F.Cu" "F.Mask" "F.Paste")
			(net "GND")
		)
		(pad "CJ64" smd circle
			(at 23.82012 20.610068 180)
			(size 0.450088 0.450088)
			(layers "F.Cu" "F.Mask" "F.Paste")
			(net "M_B_CPU0_SB_DQ<10>")
		)
		(pad "CJ65" smd circle
			(at 24.75992 20.610068 180)
			(size 0.450088 0.450088)
			(layers "F.Cu" "F.Mask" "F.Paste")
			(net "GND")
		)
		(pad "CJ66" smd circle
			(at 25.699974 20.610068 180)
			(size 0.450088 0.450088)
			(layers "F.Cu" "F.Mask" "F.Paste")
			(net "M_F_CPU0_SB_DQ<9>")
		)
		(pad "CJ67" smd circle
			(at 26.640028 20.610068 180)
			(size 0.450088 0.450088)
			(layers "F.Cu" "F.Mask" "F.Paste")
			(net "M_F_CPU0_SB_DQ<10>")
		)
		(pad "CJ68" smd circle
			(at 27.580082 20.610068 180)
			(size 0.450088 0.450088)
			(layers "F.Cu" "F.Mask" "F.Paste")
			(net "GND")
		)
		(pad "CJ69" smd circle
			(at 28.519882 20.610068 180)
			(size 0.450088 0.450088)
			(layers "F.Cu" "F.Mask" "F.Paste")
			(net "M_E_CPU0_SB_DQ<9>")
		)
		(pad "CJ70" smd circle
			(at 29.459936 20.610068 180)
			(size 0.450088 0.450088)
			(layers "F.Cu" "F.Mask" "F.Paste")
			(net "GND")
		)
		(pad "CJ71" smd circle
			(at 30.39999 20.610068 180)
			(size 0.450088 0.450088)
			(layers "F.Cu" "F.Mask" "F.Paste")
			(net "M_E_CPU0_SB_DQ<10>")
		)
		(pad "CJ72" smd circle
			(at 31.340044 20.610068 180)
			(size 0.450088 0.450088)
			(layers "F.Cu" "F.Mask" "F.Paste")
			(net "GND")
		)
		(pad "CJ73" smd circle
			(at 32.280098 20.610068 180)
			(size 0.450088 0.450088)
			(layers "F.Cu" "F.Mask" "F.Paste")
			(net "M_A_CPU0_SB_DQ<9>")
		)
		(pad "CJ74" smd circle
			(at 33.219898 20.610068 180)
			(size 0.450088 0.450088)
			(layers "F.Cu" "F.Mask" "F.Paste")
			(net "M_A_CPU0_SB_DQ<10>")
		)
		(pad "CJ75" smd circle
			(at 34.159952 20.610068 180)
			(size 0.450088 0.450088)
			(layers "F.Cu" "F.Mask" "F.Paste")
			(net "GND")
		)
		(pad "CK2" smd circle
			(at -33.990026 21.420074 180)
			(size 0.450088 0.450088)
			(layers "F.Cu" "F.Mask" "F.Paste")
			(net "M_G_CPU0_SB_DQS_DP<1>")
		)
		(pad "CK3" smd circle
			(at -33.049972 21.420074 180)
			(size 0.450088 0.450088)
			(layers "F.Cu" "F.Mask" "F.Paste")
			(net "GND")
		)
		(pad "CK4" smd circle
			(at -32.109918 21.420074 180)
			(size 0.450088 0.450088)
			(layers "F.Cu" "F.Mask" "F.Paste")
			(net "M_G_CPU0_SB_DQ<11>")
		)
		(pad "CK5" smd circle
			(at -31.170118 21.420074 180)
			(size 0.450088 0.450088)
			(layers "F.Cu" "F.Mask" "F.Paste")
			(net "PVDD11_S3_P0")
		)
		(pad "CK6" smd circle
			(at -30.230064 21.420074 180)
			(size 0.450088 0.450088)
			(layers "F.Cu" "F.Mask" "F.Paste")
			(net "M_K_CPU0_SB_DQS_DP<1>")
		)
		(pad "CK7" smd circle
			(at -29.29001 21.420074 180)
			(size 0.450088 0.450088)
			(layers "F.Cu" "F.Mask" "F.Paste")
			(net "M_K_CPU0_SB_DQ<11>")
		)
		(pad "CK8" smd circle
			(at -28.349956 21.420074 180)
			(size 0.450088 0.450088)
			(layers "F.Cu" "F.Mask" "F.Paste")
			(net "GND")
		)
		(pad "CK9" smd circle
			(at -27.409902 21.420074 180)
			(size 0.450088 0.450088)
			(layers "F.Cu" "F.Mask" "F.Paste")
			(net "M_L_CPU0_SB_DQS_DP<1>")
		)
		(pad "CK10" smd circle
			(at -26.470102 21.420074 180)
			(size 0.450088 0.450088)
			(layers "F.Cu" "F.Mask" "F.Paste")
			(net "GND")
		)
		(pad "CK11" smd circle
			(at -25.530048 21.420074 180)
			(size 0.450088 0.450088)
			(layers "F.Cu" "F.Mask" "F.Paste")
			(net "M_L_CPU0_SB_DQ<11>")
		)
		(pad "CK12" smd circle
			(at -24.589994 21.420074 180)
			(size 0.450088 0.450088)
			(layers "F.Cu" "F.Mask" "F.Paste")
			(net "PVDD11_S3_P0")
		)
		(pad "CK13" smd circle
			(at -23.64994 21.420074 180)
			(size 0.450088 0.450088)
			(layers "F.Cu" "F.Mask" "F.Paste")
			(net "M_H_CPU0_SB_DQS_DP<1>")
		)
		(pad "CK14" smd circle
			(at -22.709886 21.420074 180)
			(size 0.450088 0.450088)
			(layers "F.Cu" "F.Mask" "F.Paste")
			(net "M_H_CPU0_SB_DQ<11>")
		)
		(pad "CK15" smd circle
			(at -21.770086 21.420074 180)
			(size 0.450088 0.450088)
			(layers "F.Cu" "F.Mask" "F.Paste")
			(net "GND")
		)
		(pad "CK16" smd circle
			(at -20.830032 21.420074 180)
			(size 0.450088 0.450088)
			(layers "F.Cu" "F.Mask" "F.Paste")
			(net "M_J_CPU0_SB_DQS_DP<1>")
		)
		(pad "CK17" smd circle
			(at -19.889978 21.420074 180)
			(size 0.450088 0.450088)
			(layers "F.Cu" "F.Mask" "F.Paste")
			(net "GND")
		)
		(pad "CK18" smd circle
			(at -18.949924 21.420074 180)
			(size 0.450088 0.450088)
			(layers "F.Cu" "F.Mask" "F.Paste")
			(net "M_J_CPU0_SB_DQ<11>")
		)
		(pad "CK19" smd circle
			(at -18.010124 21.420074 180)
			(size 0.450088 0.450088)
			(layers "F.Cu" "F.Mask" "F.Paste")
			(net "PVDD11_S3_P0")
		)
		(pad "CK20" smd circle
			(at -17.07007 21.420074 180)
			(size 0.450088 0.450088)
			(layers "F.Cu" "F.Mask" "F.Paste")
			(net "M_I_CPU0_SB_DQS_DP<1>")
		)
		(pad "CK21" smd circle
			(at -16.130016 21.420074 180)
			(size 0.450088 0.450088)
			(layers "F.Cu" "F.Mask" "F.Paste")
			(net "M_I_CPU0_SB_DQ<11>")
		)
		(pad "CK22" smd circle
			(at -15.189962 21.420074 180)
			(size 0.450088 0.450088)
			(layers "F.Cu" "F.Mask" "F.Paste")
			(net "GND")
		)
		(pad "CK23" smd circle
			(at -14.249908 21.420074 180)
			(size 0.450088 0.450088)
			(layers "F.Cu" "F.Mask" "F.Paste")
			(net "GND")
		)
		(pad "CK24" smd circle
			(at -13.310108 21.420074 180)
			(size 0.450088 0.450088)
			(layers "F.Cu" "F.Mask" "F.Paste")
			(net "GND")
		)
		(pad "CK25" smd circle
			(at -12.370054 21.420074 180)
			(size 0.450088 0.450088)
			(layers "F.Cu" "F.Mask" "F.Paste")
			(net "GND")
		)
		(pad "CK26" smd circle
			(at -11.43 21.420074 180)
			(size 0.450088 0.450088)
			(layers "F.Cu" "F.Mask" "F.Paste")
			(net "GND")
		)
		(pad "CK27" smd circle
			(at -10.489946 21.420074 180)
			(size 0.450088 0.450088)
			(layers "F.Cu" "F.Mask" "F.Paste")
			(net "GND")
		)
		(pad "CK28" smd circle
			(at -9.549892 21.420074 180)
			(size 0.450088 0.450088)
			(layers "F.Cu" "F.Mask" "F.Paste")
			(net "GND")
		)
		(pad "CK29" smd circle
			(at -8.610092 21.420074 180)
			(size 0.450088 0.450088)
			(layers "F.Cu" "F.Mask" "F.Paste")
			(net "TP_CPU0_TEST5_CCD9")
		)
		(pad "CK30" smd circle
			(at -7.670038 21.420074 180)
			(size 0.450088 0.450088)
			(layers "F.Cu" "F.Mask" "F.Paste")
			(net "TP_CPU0_TEST4_CCD9")
		)
		(pad "CK31" smd circle
			(at -6.729984 21.420074 180)
			(size 0.450088 0.450088)
			(layers "F.Cu" "F.Mask" "F.Paste")
			(net "GND")
		)
		(pad "CK32" smd circle
			(at -5.78993 21.420074 180)
			(size 0.450088 0.450088)
			(layers "F.Cu" "F.Mask" "F.Paste")
			(net "GND")
		)
		(pad "CK33" smd circle
			(at -4.849876 21.420074 180)
			(size 0.450088 0.450088)
			(layers "F.Cu" "F.Mask" "F.Paste")
			(net "GND")
		)
		(pad "CK34" smd circle
			(at -3.910076 21.420074 180)
			(size 0.450088 0.450088)
			(layers "F.Cu" "F.Mask" "F.Paste")
			(net "GND")
		)
		(pad "CK35" smd circle
			(at -2.970022 21.420074 180)
			(size 0.450088 0.450088)
			(layers "F.Cu" "F.Mask" "F.Paste")
			(net "PVDDCR_CPU1_P0")
		)
		(pad "CK36" smd circle
			(at -2.029968 21.420074 180)
			(size 0.450088 0.450088)
			(layers "F.Cu" "F.Mask" "F.Paste")
			(net "PVDDCR_CPU1_P0")
		)
		(pad "CK37" smd circle
			(at -1.089914 21.420074 180)
			(size 0.450088 0.450088)
			(layers "F.Cu" "F.Mask" "F.Paste")
			(net "GND")
		)
		(pad "CK39" smd circle
			(at 0.78994 21.420074 180)
			(size 0.450088 0.450088)
			(layers "F.Cu" "F.Mask" "F.Paste")
			(net "GND")
		)
		(pad "CK40" smd circle
			(at 1.729994 21.420074 180)
			(size 0.450088 0.450088)
			(layers "F.Cu" "F.Mask" "F.Paste")
			(net "PVDDCR_CPU1_P0")
		)
		(pad "CK41" smd circle
			(at 2.670048 21.420074 180)
			(size 0.450088 0.450088)
			(layers "F.Cu" "F.Mask" "F.Paste")
			(net "PVDDCR_CPU1_P0")
		)
		(pad "CK42" smd circle
			(at 3.610102 21.420074 180)
			(size 0.450088 0.450088)
			(layers "F.Cu" "F.Mask" "F.Paste")
			(net "GND")
		)
		(pad "CK43" smd circle
			(at 4.549902 21.420074 180)
			(size 0.450088 0.450088)
			(layers "F.Cu" "F.Mask" "F.Paste")
			(net "GND")
		)
		(pad "CK44" smd circle
			(at 5.489956 21.420074 180)
			(size 0.450088 0.450088)
			(layers "F.Cu" "F.Mask" "F.Paste")
			(net "GND")
		)
		(pad "CK45" smd circle
			(at 6.43001 21.420074 180)
			(size 0.450088 0.450088)
			(layers "F.Cu" "F.Mask" "F.Paste")
			(net "GND")
		)
		(pad "CK46" smd circle
			(at 7.370064 21.420074 180)
			(size 0.450088 0.450088)
			(layers "F.Cu" "F.Mask" "F.Paste")
			(net "TP_CPU0_TEST47_CCD2")
		)
		(pad "CK47" smd circle
			(at 8.310118 21.420074 180)
			(size 0.450088 0.450088)
			(layers "F.Cu" "F.Mask" "F.Paste")
			(net "TP_CPU0_TEST5_CCD10")
		)
		(pad "CK48" smd circle
			(at 9.249918 21.420074 180)
			(size 0.450088 0.450088)
			(layers "F.Cu" "F.Mask" "F.Paste")
			(net "GND")
		)
		(pad "CK49" smd circle
			(at 10.189972 21.420074 180)
			(size 0.450088 0.450088)
			(layers "F.Cu" "F.Mask" "F.Paste")
			(net "GND")
		)
		(pad "CK50" smd circle
			(at 11.130026 21.420074 180)
			(size 0.450088 0.450088)
			(layers "F.Cu" "F.Mask" "F.Paste")
			(net "GND")
		)
		(pad "CK51" smd circle
			(at 12.07008 21.420074 180)
			(size 0.450088 0.450088)
			(layers "F.Cu" "F.Mask" "F.Paste")
			(net "GND")
		)
		(pad "CK52" smd circle
			(at 13.00988 21.420074 180)
			(size 0.450088 0.450088)
			(layers "F.Cu" "F.Mask" "F.Paste")
			(net "GND")
		)
		(pad "CK53" smd circle
			(at 13.949934 21.420074 180)
			(size 0.450088 0.450088)
			(layers "F.Cu" "F.Mask" "F.Paste")
			(net "GND")
		)
		(pad "CK54" smd circle
			(at 14.889988 21.420074 180)
			(size 0.450088 0.450088)
			(layers "F.Cu" "F.Mask" "F.Paste")
			(net "GND")
		)
		(pad "CK55" smd circle
			(at 15.830042 21.420074 180)
			(size 0.450088 0.450088)
			(layers "F.Cu" "F.Mask" "F.Paste")
			(net "M_C_CPU0_SB_DQ<11>")
		)
		(pad "CK56" smd circle
			(at 16.770096 21.420074 180)
			(size 0.450088 0.450088)
			(layers "F.Cu" "F.Mask" "F.Paste")
			(net "M_C_CPU0_SB_DQS_DP<1>")
		)
		(pad "CK57" smd circle
			(at 17.709896 21.420074 180)
			(size 0.450088 0.450088)
			(layers "F.Cu" "F.Mask" "F.Paste")
			(net "PVDDIO_P0")
		)
		(pad "CK58" smd circle
			(at 18.64995 21.420074 180)
			(size 0.450088 0.450088)
			(layers "F.Cu" "F.Mask" "F.Paste")
			(net "M_D_CPU0_SB_DQ<11>")
		)
		(pad "CK59" smd circle
			(at 19.590004 21.420074 180)
			(size 0.450088 0.450088)
			(layers "F.Cu" "F.Mask" "F.Paste")
			(net "GND")
		)
		(pad "CK60" smd circle
			(at 20.530058 21.420074 180)
			(size 0.450088 0.450088)
			(layers "F.Cu" "F.Mask" "F.Paste")
			(net "M_D_CPU0_SB_DQS_DP<1>")
		)
		(pad "CK61" smd circle
			(at 21.470112 21.420074 180)
			(size 0.450088 0.450088)
			(layers "F.Cu" "F.Mask" "F.Paste")
			(net "GND")
		)
		(pad "CK62" smd circle
			(at 22.409912 21.420074 180)
			(size 0.450088 0.450088)
			(layers "F.Cu" "F.Mask" "F.Paste")
			(net "M_B_CPU0_SB_DQ<11>")
		)
		(pad "CK63" smd circle
			(at 23.349966 21.420074 180)
			(size 0.450088 0.450088)
			(layers "F.Cu" "F.Mask" "F.Paste")
			(net "M_B_CPU0_SB_DQS_DP<1>")
		)
		(pad "CK64" smd circle
			(at 24.29002 21.420074 180)
			(size 0.450088 0.450088)
			(layers "F.Cu" "F.Mask" "F.Paste")
			(net "PVDDIO_P0")
		)
		(pad "CK65" smd circle
			(at 25.230074 21.420074 180)
			(size 0.450088 0.450088)
			(layers "F.Cu" "F.Mask" "F.Paste")
			(net "M_F_CPU0_SB_DQ<11>")
		)
		(pad "CK66" smd circle
			(at 26.170128 21.420074 180)
			(size 0.450088 0.450088)
			(layers "F.Cu" "F.Mask" "F.Paste")
			(net "GND")
		)
		(pad "CK67" smd circle
			(at 27.109928 21.420074 180)
			(size 0.450088 0.450088)
			(layers "F.Cu" "F.Mask" "F.Paste")
			(net "M_F_CPU0_SB_DQS_DP<1>")
		)
		(pad "CK68" smd circle
			(at 28.049982 21.420074 180)
			(size 0.450088 0.450088)
			(layers "F.Cu" "F.Mask" "F.Paste")
			(net "GND")
		)
		(pad "CK69" smd circle
			(at 28.990036 21.420074 180)
			(size 0.450088 0.450088)
			(layers "F.Cu" "F.Mask" "F.Paste")
			(net "M_E_CPU0_SB_DQ<11>")
		)
		(pad "CK70" smd circle
			(at 29.93009 21.420074 180)
			(size 0.450088 0.450088)
			(layers "F.Cu" "F.Mask" "F.Paste")
			(net "M_E_CPU0_SB_DQS_DP<1>")
		)
		(pad "CK71" smd circle
			(at 30.86989 21.420074 180)
			(size 0.450088 0.450088)
			(layers "F.Cu" "F.Mask" "F.Paste")
			(net "PVDDIO_P0")
		)
		(pad "CK72" smd circle
			(at 31.809944 21.420074 180)
			(size 0.450088 0.450088)
			(layers "F.Cu" "F.Mask" "F.Paste")
			(net "M_A_CPU0_SB_DQ<11>")
		)
		(pad "CK73" smd circle
			(at 32.749998 21.420074 180)
			(size 0.450088 0.450088)
			(layers "F.Cu" "F.Mask" "F.Paste")
			(net "GND")
		)
		(pad "CK74" smd circle
			(at 33.690052 21.420074 180)
			(size 0.450088 0.450088)
			(layers "F.Cu" "F.Mask" "F.Paste")
			(net "M_A_CPU0_SB_DQS_DP<1>")
		)
		(pad "CL1" smd circle
			(at -34.459926 22.23008 180)
			(size 0.450088 0.450088)
			(layers "F.Cu" "F.Mask" "F.Paste")
			(net "GND")
		)
		(pad "CL2" smd circle
			(at -33.519872 22.23008 180)
			(size 0.450088 0.450088)
			(layers "F.Cu" "F.Mask" "F.Paste")
			(net "M_G_CPU0_SB_DQS_DN<1>")
		)
		(pad "CL3" smd circle
			(at -32.580072 22.23008 180)
			(size 0.450088 0.450088)
			(layers "F.Cu" "F.Mask" "F.Paste")
			(net "M_G_CPU0_SB_DQS_DN<6>")
		)
		(pad "CL4" smd circle
			(at -31.640018 22.23008 180)
			(size 0.450088 0.450088)
			(layers "F.Cu" "F.Mask" "F.Paste")
			(net "GND")
		)
		(pad "CL5" smd circle
			(at -30.699964 22.23008 180)
			(size 0.450088 0.450088)
			(layers "F.Cu" "F.Mask" "F.Paste")
			(net "M_K_CPU0_SB_DQS_DN<1>")
		)
		(pad "CL6" smd circle
			(at -29.75991 22.23008 180)
			(size 0.450088 0.450088)
			(layers "F.Cu" "F.Mask" "F.Paste")
			(net "GND")
		)
		(pad "CL7" smd circle
			(at -28.82011 22.23008 180)
			(size 0.450088 0.450088)
			(layers "F.Cu" "F.Mask" "F.Paste")
			(net "M_K_CPU0_SB_DQS_DN<6>")
		)
		(pad "CL8" smd circle
			(at -27.880056 22.23008 180)
			(size 0.450088 0.450088)
			(layers "F.Cu" "F.Mask" "F.Paste")
			(net "GND")
		)
		(pad "CL9" smd circle
			(at -26.940002 22.23008 180)
			(size 0.450088 0.450088)
			(layers "F.Cu" "F.Mask" "F.Paste")
			(net "M_L_CPU0_SB_DQS_DN<1>")
		)
		(pad "CL10" smd circle
			(at -25.999948 22.23008 180)
			(size 0.450088 0.450088)
			(layers "F.Cu" "F.Mask" "F.Paste")
			(net "M_L_CPU0_SB_DQS_DN<6>")
		)
		(pad "CL11" smd circle
			(at -25.059894 22.23008 180)
			(size 0.450088 0.450088)
			(layers "F.Cu" "F.Mask" "F.Paste")
			(net "GND")
		)
		(pad "CL12" smd circle
			(at -24.120094 22.23008 180)
			(size 0.450088 0.450088)
			(layers "F.Cu" "F.Mask" "F.Paste")
			(net "M_H_CPU0_SB_DQS_DN<1>")
		)
		(pad "CL13" smd circle
			(at -23.18004 22.23008 180)
			(size 0.450088 0.450088)
			(layers "F.Cu" "F.Mask" "F.Paste")
			(net "GND")
		)
		(pad "CL14" smd circle
			(at -22.239986 22.23008 180)
			(size 0.450088 0.450088)
			(layers "F.Cu" "F.Mask" "F.Paste")
			(net "M_H_CPU0_SB_DQS_DN<6>")
		)
		(pad "CL15" smd circle
			(at -21.299932 22.23008 180)
			(size 0.450088 0.450088)
			(layers "F.Cu" "F.Mask" "F.Paste")
			(net "GND")
		)
		(pad "CL16" smd circle
			(at -20.359878 22.23008 180)
			(size 0.450088 0.450088)
			(layers "F.Cu" "F.Mask" "F.Paste")
			(net "M_J_CPU0_SB_DQS_DN<1>")
		)
		(pad "CL17" smd circle
			(at -19.420078 22.23008 180)
			(size 0.450088 0.450088)
			(layers "F.Cu" "F.Mask" "F.Paste")
			(net "M_J_CPU0_SB_DQS_DN<6>")
		)
		(pad "CL18" smd circle
			(at -18.480024 22.23008 180)
			(size 0.450088 0.450088)
			(layers "F.Cu" "F.Mask" "F.Paste")
			(net "GND")
		)
		(pad "CL19" smd circle
			(at -17.53997 22.23008 180)
			(size 0.450088 0.450088)
			(layers "F.Cu" "F.Mask" "F.Paste")
			(net "M_I_CPU0_SB_DQS_DN<1>")
		)
		(pad "CL20" smd circle
			(at -16.599916 22.23008 180)
			(size 0.450088 0.450088)
			(layers "F.Cu" "F.Mask" "F.Paste")
			(net "GND")
		)
		(pad "CL21" smd circle
			(at -15.660116 22.23008 180)
			(size 0.450088 0.450088)
			(layers "F.Cu" "F.Mask" "F.Paste")
			(net "M_I_CPU0_SB_DQS_DN<6>")
		)
		(pad "CL22" smd circle
			(at -14.720062 22.23008 180)
			(size 0.450088 0.450088)
			(layers "F.Cu" "F.Mask" "F.Paste")
			(net "GND")
		)
		(pad "CL23" smd circle
			(at -13.780008 22.23008 180)
			(size 0.450088 0.450088)
			(layers "F.Cu" "F.Mask" "F.Paste")
			(net "P5E_CPU0_P2_RX_DP<13>")
		)
		(pad "CL24" smd circle
			(at -12.839954 22.23008 180)
			(size 0.450088 0.450088)
			(layers "F.Cu" "F.Mask" "F.Paste")
			(net "P5E_CPU0_P2_RX_DN<13>")
		)
		(pad "CL25" smd circle
			(at -11.8999 22.23008 180)
			(size 0.450088 0.450088)
			(layers "F.Cu" "F.Mask" "F.Paste")
			(net "GND")
		)
		(pad "CL26" smd circle
			(at -10.9601 22.23008 180)
			(size 0.450088 0.450088)
			(layers "F.Cu" "F.Mask" "F.Paste")
			(net "P5E_CPU0_P2_RX_DP<9>")
		)
	)
)
